#ISCELL
  mstr_misc dns *
  *
#ISCELL
  pure_quanta quanta_title_block_c *
  *
#ISCELL
  pure_quanta_power cad_note *
  *
#CELL
  pure_quanta q_res *
  page148_i244
#CELL
  pure_quanta q_res *
  page148_i245
#CELL
  pure_quanta q_res *
  page148_i246
#ISCELL
  pure_quanta_power universal_gnd *
  page148_i247
#ISCELL
  pure_quanta_power universal_power *
  page148_i248
#CELL
  pure_quanta q_res *
  page148_i249
#CELL
  pure_quanta q_res *
  page148_i250
#ISCELL
  standard offpage *
  page148_i251
#ISCELL
  standard offpage *
  page148_i252
#ISCELL
  standard offpage *
  page148_i253
#ISCELL
  standard offpage *
  page148_i254
#CELL
  pure_quanta q_res *
  page148_i255
#CELL
  pure_quanta q_res *
  page148_i256
#CELL
  pure_quanta q_res *
  page148_i257
#CELL
  pure_quanta q_res *
  page148_i258
#ISCELL
  pure_quanta_power universal_gnd *
  page148_i259
#ISCELL
  pure_quanta_power universal_power *
  page148_i260
#CELL
  pure_quanta q_res *
  page148_i261
#ISCELL
  standard offpage *
  page148_i262
#ISCELL
  standard offpage *
  page148_i263
#ISCELL
  standard offpage *
  page148_i264
#ISCELL
  standard offpage *
  page148_i265
#CELL
  pure_quanta 74lv4052pw *
  page148_i266
#ISCELL
  pure_quanta_power universal_gnd *
  page148_i267
#ISCELL
  pure_quanta_power universal_power *
  page148_i292
#CELL
  pure_quanta q_cap *
  page148_i293
#ISCELL
  pure_quanta_power universal_gnd *
  page148_i294
#ISCELL
  pure_quanta_power universal_power *
  page148_i295
#ISCELL
  standard offpage *
  page148_i296
#ISCELL
  standard offpage *
  page148_i297
#ISCELL
  pure_quanta_power universal_power *
  page148_i298
#CELL
  pure_quanta q_cap *
  page148_i299
#ISCELL
  pure_quanta_power universal_gnd *
  page148_i300
#ISCELL
  pure_quanta_power universal_gnd *
  page148_i301
#CELL
  pure_quanta 74lv4052pw *
  page148_i302
#CELL
  pure_quanta q_res *
  page148_i305
#CELL
  pure_quanta q_res *
  page148_i306
#ISCELL
  pure_quanta_power universal_gnd *
  page148_i307
#ISCELL
  pure_quanta_power universal_power *
  page148_i308
#CELL
  pure_quanta q_res *
  page148_i309
#CELL
  pure_quanta q_res *
  page148_i310
#ISCELL
  pure_quanta_power universal_gnd *
  page148_i311
#ISCELL
  standard offpage *
  page148_i312
#ISCELL
  standard offpage *
  page148_i313
#ISCELL
  standard offpage *
  page148_i314
#ISCELL
  standard offpage *
  page148_i315
#ISCELL
  standard offpage *
  page148_i327
#ISCELL
  standard offpage *
  page148_i331
#CELL
  pure_quanta q_res *
  page148_i332
#ISCELL
  standard offpage *
  page148_i336
#ISCELL
  pure_quanta_power universal_power *
  page148_i337
#CELL
  pure_quanta q_res *
  page148_i339
#CELL
  pure_quanta sn74lvc1g07dbvr *
  page148_i340
#ISCELL
  pure_quanta_power universal_power *
  page148_i341
#CELL
  pure_quanta q_cap *
  page148_i342
#ISCELL
  pure_quanta_power universal_gnd *
  page148_i343
#ISCELL
  pure_quanta_power universal_gnd *
  page148_i344
#ISCELL
  standard offpage *
  page148_i347
#CELL
  pure_quanta q_res *
  page148_i349
#ISCELL
  standard offpage *
  page148_i351
#CELL
  pure_quanta q_res *
  page148_i352
#ISCELL
  standard offpage *
  page148_i355
#CELL
  pure_quanta q_res *
  page148_i357
#ISCELL
  standard offpage *
  page148_i362
#CELL
  pure_quanta q_res *
  page148_i363
#ISCELL
  standard offpage *
  page148_i365
#CELL
  pure_quanta q_res *
  page148_i366
#ISCELL
  standard offpage *
  page148_i367
#CELL
  pure_quanta q_res *
  page148_i368
#CELL
  pure_quanta q_res *
  page148_i369
#ISCELL
  pure_quanta_power universal_gnd *
  page148_i370
#ISCELL
  pure_quanta_power universal_gnd *
  page148_i372
#CELL
  pure_quanta q_res *
  page148_i375
#CELL
  pure_quanta q_res *
  page148_i376
#CELL
  pure_quanta q_res *
  page148_i378
#ISCELL
  pure_quanta_power universal_gnd *
  page148_i379
#ISCELL
  pure_quanta_power universal_power *
  page148_i380
#CELL
  pure_quanta q_res *
  page148_i381
#CELL
  pure_quanta q_res *
  page148_i383
#CELL
  pure_quanta q_res *
  page148_i384
#ISCELL
  pure_quanta_power universal_power *
  page148_i385
#CELL
  pure_quanta conn3_210hp1030br1 *
  page148_i386
#CELL
  pure_quanta conn3_210hp1030br1 *
  page148_i387
#CELL
  pure_quanta q_res *
  page148_i388
